# T6G (Grand Teton) — schematic netlist excerpt (pin names and nets, part order shuffled) for the footprints in the layout excerpt that follows; sources: Cadence DE-HDL packaged netlist, KiCad conversion of 04192023_DAF0TMB3IC0_F0TG_MB_C_brd_V02_OCP.brd

PR443  Q_RES  0 5% EMPTY  pkg 0402LF  page 201 : A = PVDDCR_CPU1_P0_PVCC ; B = P3V3_AUX
R3593  Q_RES  33.2 1% CHIP  pkg 0402LF  page 251 : A = SMB_INA230_3V3AUX_SDA ; B = SMB_INA230_5_3V3AUX_SDA_R

(kicad_pcb
	(version 20260206)
	(generator "pcbnew")
	(generator_version "10.0")
	(general
		(thickness 1.6)
		(legacy_teardrops no)
	)
	(paper "A4")
	(title_block
		(title "04192023_DAF0TMB3IC0_F0TG_MB_C_brd_V02_OCP.brd")
		(comment 1 "Grand Teton / footprints 1739-1740 of 8354")
	)
	(layers
		(0 "F.Cu" signal "TOP")
		(4 "In1.Cu" signal "GND")
		(6 "In2.Cu" signal "IN1")
		(8 "In3.Cu" signal "GND1")
		(10 "In4.Cu" signal "IN2")
		(12 "In5.Cu" signal "GND2")
		(14 "In6.Cu" signal "IN3")
		(16 "In7.Cu" signal "GND3")
		(18 "In8.Cu" signal "VCC")
		(20 "In9.Cu" signal "VCC1")
		(22 "In10.Cu" signal "GND4")
		(24 "In11.Cu" signal "IN4")
		(26 "In12.Cu" signal "GND5")
		(28 "In13.Cu" signal "IN5")
		(30 "In14.Cu" signal "GND6")
		(32 "In15.Cu" signal "IN6")
		(34 "In16.Cu" signal "GND7")
		(2 "B.Cu" signal "BOTTOM")
		(9 "F.Adhes" user "F.Adhesive")
		(11 "B.Adhes" user "B.Adhesive")
		(13 "F.Paste" user "Package Geometry/Pastemask Top")
		(15 "B.Paste" user "Package Geometry/Pastemask Bottom")
		(5 "F.SilkS" user "Ref Des/Silkscreen Top")
		(7 "B.SilkS" user "Ref Des/Silkscreen Bottom")
		(1 "F.Mask" user "Board Geometry/Soldermask Top")
		(3 "B.Mask" user "Board Geometry/Soldermask Bottom")
		(17 "Dwgs.User" user "User.Drawings")
		(19 "Cmts.User" user "User.Comments")
		(21 "Eco1.User" user "User.Eco1")
		(23 "Eco2.User" user "User.Eco2")
		(25 "Edge.Cuts" user "Board Geometry/Outline")
		(27 "Margin" user)
		(31 "F.CrtYd" user "Package Geometry/Place Bound Top")
		(29 "B.CrtYd" user "Package Geometry/Place Bound Bottom")
		(35 "F.Fab" user "Ref Des/Assembly Top")
		(33 "B.Fab" user "Ref Des/Assembly Bottom")
	)
	(footprint ""
		(layer "F.Cu")
		(at 215.956134 -32.857948 180)
		(property "Reference" "R3593"
			(at 0 0 180)
			(layer "F.SilkS")
			(hide yes)
			(effects
				(font
					(size 1.27 1.27)
				)
			)
		)
		(property "Value" ""
			(at 0 0 180)
			(layer "F.Fab")
			(effects
				(font
					(size 1.27 1.27)
				)
			)
		)
		(duplicate_pad_numbers_are_jumpers no)
		(fp_line
			(start 0.7874 0.4064)
			(end -0.7874 0.4064)
			(stroke
				(width 0.1524)
				(type default)
			)
			(layer "F.SilkS")
		)
		(fp_line
			(start 0.7874 -0.4064)
			(end 0.7874 0.4064)
			(stroke
				(width 0.1524)
				(type default)
			)
			(layer "F.SilkS")
		)
		(fp_line
			(start -0.7874 0.4064)
			(end -0.7874 -0.4064)
			(stroke
				(width 0.1524)
				(type default)
			)
			(layer "F.SilkS")
		)
		(fp_line
			(start -0.7874 -0.4064)
			(end 0.7874 -0.4064)
			(stroke
				(width 0.1524)
				(type default)
			)
			(layer "F.SilkS")
		)
		(fp_line
			(start 0.67945 0.3048)
			(end 0.120396 0.3048)
			(stroke
				(width 0.1)
				(type default)
			)
			(layer "F.Fab")
		)
		(fp_line
			(start 0.67945 -0.3048)
			(end 0.67945 0.3048)
			(stroke
				(width 0.1)
				(type default)
			)
			(layer "F.Fab")
		)
		(fp_line
			(start 0.12065 -0.2794)
			(end 0.12065 -0.3048)
			(stroke
				(width 0.1)
				(type default)
			)
			(layer "F.Fab")
		)
		(fp_line
			(start 0.12065 -0.3048)
			(end 0.67945 -0.3048)
			(stroke
				(width 0.1)
				(type default)
			)
			(layer "F.Fab")
		)
		(fp_line
			(start 0.120396 0.3048)
			(end 0.120396 0.2794)
			(stroke
				(width 0.1)
				(type default)
			)
			(layer "F.Fab")
		)
		(fp_line
			(start 0.120396 0.2794)
			(end -0.12065 0.2794)
			(stroke
				(width 0.1)
				(type default)
			)
			(layer "F.Fab")
		)
		(fp_line
			(start -0.12065 0.3048)
			(end -0.67945 0.3048)
			(stroke
				(width 0.1)
				(type default)
			)
			(layer "F.Fab")
		)
		(fp_line
			(start -0.12065 0.2794)
			(end -0.12065 0.3048)
			(stroke
				(width 0.1)
				(type default)
			)
			(layer "F.Fab")
		)
		(fp_line
			(start -0.12065 -0.2794)
			(end 0.12065 -0.2794)
			(stroke
				(width 0.1)
				(type default)
			)
			(layer "F.Fab")
		)
		(fp_line
			(start -0.12065 -0.305054)
			(end -0.12065 -0.2794)
			(stroke
				(width 0.1)
				(type default)
			)
			(layer "F.Fab")
		)
		(fp_line
			(start -0.67945 0.3048)
			(end -0.67945 -0.305054)
			(stroke
				(width 0.1)
				(type default)
			)
			(layer "F.Fab")
		)
		(fp_line
			(start -0.67945 -0.305054)
			(end -0.12065 -0.305054)
			(stroke
				(width 0.1)
				(type default)
			)
			(layer "F.Fab")
		)
		(pad "1" smd circle
			(at -0.40005 0 180)
			(size 0 0)
			(layers "F.Cu" "F.Mask" "F.Paste")
			(net "SMB_INA230_3V3AUX_SDA")
		)
		(pad "2" smd circle
			(at 0.40005 0 180)
			(size 0 0)
			(layers "F.Cu" "F.Mask" "F.Paste")
			(net "SMB_INA230_5_3V3AUX_SDA_R")
		)
	)
	(footprint ""
		(layer "F.Cu")
		(at 270.856202 -351.5487 90)
		(property "Reference" "PR443"
			(at 0 0 90)
			(layer "F.SilkS")
			(hide yes)
			(effects
				(font
					(size 1.27 1.27)
				)
			)
		)
		(property "Value" ""
			(at 0 0 90)
			(layer "F.Fab")
			(effects
				(font
					(size 1.27 1.27)
				)
			)
		)
		(duplicate_pad_numbers_are_jumpers no)
		(fp_line
			(start 0.7874 -0.4064)
			(end 0.7874 0.4064)
			(stroke
				(width 0.1524)
				(type default)
			)
			(layer "F.SilkS")
		)
		(fp_line
			(start -0.7874 -0.4064)
			(end 0.7874 -0.4064)
			(stroke
				(width 0.1524)
				(type default)
			)
			(layer "F.SilkS")
		)
		(fp_line
			(start 0.7874 0.4064)
			(end -0.7874 0.4064)
			(stroke
				(width 0.1524)
				(type default)
			)
			(layer "F.SilkS")
		)
		(fp_line
			(start -0.7874 0.4064)
			(end -0.7874 -0.4064)
			(stroke
				(width 0.1524)
				(type default)
			)
			(layer "F.SilkS")
		)
		(fp_line
			(start -0.12065 -0.305054)
			(end -0.12065 -0.2794)
			(stroke
				(width 0.1)
				(type default)
			)
			(layer "F.Fab")
		)
		(fp_line
			(start -0.67945 -0.305054)
			(end -0.12065 -0.305054)
			(stroke
				(width 0.1)
				(type default)
			)
			(layer "F.Fab")
		)
		(fp_line
			(start 0.67945 -0.3048)
			(end 0.67945 0.3048)
			(stroke
				(width 0.1)
				(type default)
			)
			(layer "F.Fab")
		)
		(fp_line
			(start 0.12065 -0.3048)
			(end 0.67945 -0.3048)
			(stroke
				(width 0.1)
				(type default)
			)
			(layer "F.Fab")
		)
		(fp_line
			(start 0.12065 -0.2794)
			(end 0.12065 -0.3048)
			(stroke
				(width 0.1)
				(type default)
			)
			(layer "F.Fab")
		)
		(fp_line
			(start -0.12065 -0.2794)
			(end 0.12065 -0.2794)
			(stroke
				(width 0.1)
				(type default)
			)
			(layer "F.Fab")
		)
		(fp_line
			(start 0.120396 0.2794)
			(end -0.12065 0.2794)
			(stroke
				(width 0.1)
				(type default)
			)
			(layer "F.Fab")
		)
		(fp_line
			(start -0.12065 0.2794)
			(end -0.12065 0.3048)
			(stroke
				(width 0.1)
				(type default)
			)
			(layer "F.Fab")
		)
		(fp_line
			(start 0.67945 0.3048)
			(end 0.120396 0.3048)
			(stroke
				(width 0.1)
				(type default)
			)
			(layer "F.Fab")
		)
		(fp_line
			(start 0.120396 0.3048)
			(end 0.120396 0.2794)
			(stroke
				(width 0.1)
				(type default)
			)
			(layer "F.Fab")
		)
		(fp_line
			(start -0.12065 0.3048)
			(end -0.67945 0.3048)
			(stroke
				(width 0.1)
				(type default)
			)
			(layer "F.Fab")
		)
		(fp_line
			(start -0.67945 0.3048)
			(end -0.67945 -0.305054)
			(stroke
				(width 0.1)
				(type default)
			)
			(layer "F.Fab")
		)
		(pad "1" smd circle
			(at -0.40005 0 90)
			(size 0 0)
			(layers "F.Cu" "F.Mask" "F.Paste")
			(net "PVDDCR_CPU1_P0_PVCC")
		)
		(pad "2" smd circle
			(at 0.40005 0 90)
			(size 0 0)
			(layers "F.Cu" "F.Mask" "F.Paste")
			(net "P3V3_AUX")
		)
	)
)
